# T6G (Grand Teton) — schematic netlist excerpt (pin names and nets, part order shuffled) for the footprints in the layout excerpt that follows; sources: Cadence DE-HDL packaged netlist, KiCad conversion of 04192023_DAF0TMB3IC0_F0TG_MB_C_brd_V02_OCP.brd

PR3920  Q_RES  0 5% CHIP  pkg 0402LF  page 263 : A = HSC_FLT_TYPE_1 ; B = HSC_FLT_TYPE
PR3852  Q_RES  71.5K 1% EMPTY  pkg 0402LF  page 141 : A = P12V_OCP_V3_2 ; B = P12V_OCP_OV_FB_2

(kicad_pcb
	(version 20260206)
	(generator "pcbnew")
	(generator_version "10.0")
	(general
		(thickness 1.6)
		(legacy_teardrops no)
	)
	(paper "A4")
	(title_block
		(title "04192023_DAF0TMB3IC0_F0TG_MB_C_brd_V02_OCP.brd")
		(comment 1 "Grand Teton / footprints 894-895 of 8354")
	)
	(layers
		(0 "F.Cu" signal "TOP")
		(4 "In1.Cu" signal "GND")
		(6 "In2.Cu" signal "IN1")
		(8 "In3.Cu" signal "GND1")
		(10 "In4.Cu" signal "IN2")
		(12 "In5.Cu" signal "GND2")
		(14 "In6.Cu" signal "IN3")
		(16 "In7.Cu" signal "GND3")
		(18 "In8.Cu" signal "VCC")
		(20 "In9.Cu" signal "VCC1")
		(22 "In10.Cu" signal "GND4")
		(24 "In11.Cu" signal "IN4")
		(26 "In12.Cu" signal "GND5")
		(28 "In13.Cu" signal "IN5")
		(30 "In14.Cu" signal "GND6")
		(32 "In15.Cu" signal "IN6")
		(34 "In16.Cu" signal "GND7")
		(2 "B.Cu" signal "BOTTOM")
		(9 "F.Adhes" user "F.Adhesive")
		(11 "B.Adhes" user "B.Adhesive")
		(13 "F.Paste" user "Package Geometry/Pastemask Top")
		(15 "B.Paste" user "Package Geometry/Pastemask Bottom")
		(5 "F.SilkS" user "Ref Des/Silkscreen Top")
		(7 "B.SilkS" user "Ref Des/Silkscreen Bottom")
		(1 "F.Mask" user "Board Geometry/Soldermask Top")
		(3 "B.Mask" user "Board Geometry/Soldermask Bottom")
		(17 "Dwgs.User" user "User.Drawings")
		(19 "Cmts.User" user "User.Comments")
		(21 "Eco1.User" user "User.Eco1")
		(23 "Eco2.User" user "User.Eco2")
		(25 "Edge.Cuts" user "Board Geometry/Outline")
		(27 "Margin" user)
		(31 "F.CrtYd" user "Package Geometry/Place Bound Top")
		(29 "B.CrtYd" user "Package Geometry/Place Bound Bottom")
		(35 "F.Fab" user "Ref Des/Assembly Top")
		(33 "B.Fab" user "Ref Des/Assembly Bottom")
	)
	(footprint ""
		(layer "F.Cu")
		(at 61.845698 -26.99004 90)
		(property "Reference" "PR3852"
			(at 0 0 90)
			(layer "F.SilkS")
			(hide yes)
			(effects
				(font
					(size 1.27 1.27)
				)
			)
		)
		(property "Value" ""
			(at 0 0 90)
			(layer "F.Fab")
			(effects
				(font
					(size 1.27 1.27)
				)
			)
		)
		(duplicate_pad_numbers_are_jumpers no)
		(fp_line
			(start 0.7874 -0.4064)
			(end 0.7874 0.4064)
			(stroke
				(width 0.1524)
				(type default)
			)
			(layer "F.SilkS")
		)
		(fp_line
			(start -0.7874 -0.4064)
			(end 0.7874 -0.4064)
			(stroke
				(width 0.1524)
				(type default)
			)
			(layer "F.SilkS")
		)
		(fp_line
			(start 0.7874 0.4064)
			(end -0.7874 0.4064)
			(stroke
				(width 0.1524)
				(type default)
			)
			(layer "F.SilkS")
		)
		(fp_line
			(start -0.7874 0.4064)
			(end -0.7874 -0.4064)
			(stroke
				(width 0.1524)
				(type default)
			)
			(layer "F.SilkS")
		)
		(fp_line
			(start -0.12065 -0.305054)
			(end -0.12065 -0.2794)
			(stroke
				(width 0.1)
				(type default)
			)
			(layer "F.Fab")
		)
		(fp_line
			(start -0.67945 -0.305054)
			(end -0.12065 -0.305054)
			(stroke
				(width 0.1)
				(type default)
			)
			(layer "F.Fab")
		)
		(fp_line
			(start 0.67945 -0.3048)
			(end 0.67945 0.3048)
			(stroke
				(width 0.1)
				(type default)
			)
			(layer "F.Fab")
		)
		(fp_line
			(start 0.12065 -0.3048)
			(end 0.67945 -0.3048)
			(stroke
				(width 0.1)
				(type default)
			)
			(layer "F.Fab")
		)
		(fp_line
			(start 0.12065 -0.2794)
			(end 0.12065 -0.3048)
			(stroke
				(width 0.1)
				(type default)
			)
			(layer "F.Fab")
		)
		(fp_line
			(start -0.12065 -0.2794)
			(end 0.12065 -0.2794)
			(stroke
				(width 0.1)
				(type default)
			)
			(layer "F.Fab")
		)
		(fp_line
			(start 0.120396 0.2794)
			(end -0.12065 0.2794)
			(stroke
				(width 0.1)
				(type default)
			)
			(layer "F.Fab")
		)
		(fp_line
			(start -0.12065 0.2794)
			(end -0.12065 0.3048)
			(stroke
				(width 0.1)
				(type default)
			)
			(layer "F.Fab")
		)
		(fp_line
			(start 0.67945 0.3048)
			(end 0.120396 0.3048)
			(stroke
				(width 0.1)
				(type default)
			)
			(layer "F.Fab")
		)
		(fp_line
			(start 0.120396 0.3048)
			(end 0.120396 0.2794)
			(stroke
				(width 0.1)
				(type default)
			)
			(layer "F.Fab")
		)
		(fp_line
			(start -0.12065 0.3048)
			(end -0.67945 0.3048)
			(stroke
				(width 0.1)
				(type default)
			)
			(layer "F.Fab")
		)
		(fp_line
			(start -0.67945 0.3048)
			(end -0.67945 -0.305054)
			(stroke
				(width 0.1)
				(type default)
			)
			(layer "F.Fab")
		)
		(pad "1" smd circle
			(at -0.40005 0 90)
			(size 0 0)
			(layers "F.Cu" "F.Mask" "F.Paste")
			(net "P12V_OCP_V3_2")
		)
		(pad "2" smd circle
			(at 0.40005 0 90)
			(size 0 0)
			(layers "F.Cu" "F.Mask" "F.Paste")
			(net "P12V_OCP_OV_FB_2")
		)
	)
	(footprint ""
		(layer "F.Cu")
		(at 204.7621 -406.052782)
		(property "Reference" "PR3920"
			(at 0 0 0)
			(layer "F.SilkS")
			(hide yes)
			(effects
				(font
					(size 1.27 1.27)
				)
			)
		)
		(property "Value" ""
			(at 0 0 0)
			(layer "F.Fab")
			(effects
				(font
					(size 1.27 1.27)
				)
			)
		)
		(duplicate_pad_numbers_are_jumpers no)
		(fp_line
			(start -0.7874 -0.4064)
			(end 0.7874 -0.4064)
			(stroke
				(width 0.1524)
				(type default)
			)
			(layer "F.SilkS")
		)
		(fp_line
			(start -0.7874 0.4064)
			(end -0.7874 -0.4064)
			(stroke
				(width 0.1524)
				(type default)
			)
			(layer "F.SilkS")
		)
		(fp_line
			(start 0.7874 -0.4064)
			(end 0.7874 0.4064)
			(stroke
				(width 0.1524)
				(type default)
			)
			(layer "F.SilkS")
		)
		(fp_line
			(start 0.7874 0.4064)
			(end -0.7874 0.4064)
			(stroke
				(width 0.1524)
				(type default)
			)
			(layer "F.SilkS")
		)
		(fp_line
			(start -0.67945 -0.305054)
			(end -0.12065 -0.305054)
			(stroke
				(width 0.1)
				(type default)
			)
			(layer "F.Fab")
		)
		(fp_line
			(start -0.67945 0.3048)
			(end -0.67945 -0.305054)
			(stroke
				(width 0.1)
				(type default)
			)
			(layer "F.Fab")
		)
		(fp_line
			(start -0.12065 -0.305054)
			(end -0.12065 -0.2794)
			(stroke
				(width 0.1)
				(type default)
			)
			(layer "F.Fab")
		)
		(fp_line
			(start -0.12065 -0.2794)
			(end 0.12065 -0.2794)
			(stroke
				(width 0.1)
				(type default)
			)
			(layer "F.Fab")
		)
		(fp_line
			(start -0.12065 0.2794)
			(end -0.12065 0.3048)
			(stroke
				(width 0.1)
				(type default)
			)
			(layer "F.Fab")
		)
		(fp_line
			(start -0.12065 0.3048)
			(end -0.67945 0.3048)
			(stroke
				(width 0.1)
				(type default)
			)
			(layer "F.Fab")
		)
		(fp_line
			(start 0.120396 0.2794)
			(end -0.12065 0.2794)
			(stroke
				(width 0.1)
				(type default)
			)
			(layer "F.Fab")
		)
		(fp_line
			(start 0.120396 0.3048)
			(end 0.120396 0.2794)
			(stroke
				(width 0.1)
				(type default)
			)
			(layer "F.Fab")
		)
		(fp_line
			(start 0.12065 -0.3048)
			(end 0.67945 -0.3048)
			(stroke
				(width 0.1)
				(type default)
			)
			(layer "F.Fab")
		)
		(fp_line
			(start 0.12065 -0.2794)
			(end 0.12065 -0.3048)
			(stroke
				(width 0.1)
				(type default)
			)
			(layer "F.Fab")
		)
		(fp_line
			(start 0.67945 -0.3048)
			(end 0.67945 0.3048)
			(stroke
				(width 0.1)
				(type default)
			)
			(layer "F.Fab")
		)
		(fp_line
			(start 0.67945 0.3048)
			(end 0.120396 0.3048)
			(stroke
				(width 0.1)
				(type default)
			)
			(layer "F.Fab")
		)
		(pad "1" smd circle
			(at -0.40005 0)
			(size 0 0)
			(layers "F.Cu" "F.Mask" "F.Paste")
			(net "HSC_FLT_TYPE_1")
		)
		(pad "2" smd circle
			(at 0.40005 0)
			(size 0 0)
			(layers "F.Cu" "F.Mask" "F.Paste")
			(net "HSC_FLT_TYPE")
		)
	)
)
